FILE_TYPE=LIBRARY_PARTS;
primitive 'ME_DUMMY_SYMBOL';
  pin
  end_pin;
  body
    PART_NAME='ME_DUMMY_SYMBOL';
    BODY_NAME='ME_DUMMY_SYMBOL';
    PHYS_DES_PREFIX='ME';
    CLASS='MECHANICAL';
  end_body;
end_primitive;

END.
